(kicad_pcb
	(version 20221018)
	(generator pcbnew)
	(general
    (thickness 1.6)
  )
	(paper "A4")
	(title_block
    (title "NUC Computer Cluster Power Breakout HW")
    (date "2023-10-18")
    (rev "1.4.3")
    (company "Antmicro Ltd.")
		(comment 9 "footprints 103-109 of 234")
	)
	(layers
    (0 "F.Cu" mixed)
    (1 "In1.Cu" power)
    (2 "In2.Cu" mixed)
    (31 "B.Cu" power)
    (32 "B.Adhes" user "B.Adhesive")
    (33 "F.Adhes" user "F.Adhesive")
    (34 "B.Paste" user)
    (35 "F.Paste" user)
    (36 "B.SilkS" user "B.Silkscreen")
    (37 "F.SilkS" user "F.Silkscreen")
    (38 "B.Mask" user)
    (39 "F.Mask" user)
    (40 "Dwgs.User" user "User.Drawings")
    (41 "Cmts.User" user "User.Comments")
    (42 "Eco1.User" user "User.Eco1")
    (43 "Eco2.User" user "User.Eco2")
    (44 "Edge.Cuts" user)
    (45 "Margin" user)
    (46 "B.CrtYd" user "B.Courtyard")
    (47 "F.CrtYd" user "F.Courtyard")
    (48 "B.Fab" user)
    (49 "F.Fab" user)
  )
	(footprint "antmicro-footprints:C_0603_1608Metric" (layer "F.Cu")
    (at 104.547132 99.826324 -90)
    (descr "Capacitor SMD 0603")
    (tags "capacitor 0603")
    (property "Author" "Antmicro")
    (property "Dielectric" "")
    (property "License" "Apache-2.0")
    (property "MPN" "GRM188R60J226MEA0D")
    (property "Manufacturer" "Murata")
    (property "Sheetfile" "daughterboard-supply.kicad_sch")
    (property "Sheetname" "daughterboard-supply")
    (property "Val" "22u")
    (property "Voltage" "")
    (property "ki_description" "SMD Multilayer Ceramic Capacitor, 22 µF, 6.3 V, 0603 [1608 Metric], ± 20%, X5R, GRM Series")
    (property "ki_keywords" "0603, SMT, CAPACITOR, PASSIVE, CERAMIC, MLCC")
    (attr smd)
    (fp_text reference "C35" (at -4.376324 0.447132 -90) (layer "F.SilkS")
        (effects (font (size 0.7 0.7) (thickness 0.15)) (justify right bottom))
    )
    (fp_text value "C_22u_0603" (at -1.42757 1.770288 90) (layer "F.Fab")
        (effects (font (size 0.7 0.7) (thickness 0.15)) (justify right bottom))
    )
    (fp_text user "License: Apache-2.0" (at -1.682 5.895 90) (layer "F.Fab") hide
        (effects (font (size 0.7 0.7) (thickness 0.15)) (justify right bottom))
    )
    (fp_text user "Author: Antmicro" (at -1.682 4.894 90) (layer "F.Fab") hide
        (effects (font (size 0.7 0.7) (thickness 0.15)) (justify right bottom))
    )
    (fp_text user "${REFERENCE}" (at -1.682 3.895 90) (layer "F.Fab") hide
        (effects (font (size 0.7 0.7) (thickness 0.15)) (justify right bottom))
    )
    (fp_line (start -0.15 -0.4) (end 0.15 -0.4)
      (stroke (width 0.15) (type solid)) (layer "F.SilkS"))
    (fp_line (start -0.15 0.4) (end 0.15 0.4)
      (stroke (width 0.15) (type solid)) (layer "F.SilkS"))
    (fp_rect (start -1.25 -0.65) (end 1.25 0.65)
      (stroke (width 0.05) (type solid)) (fill none) (layer "F.CrtYd"))
    (fp_rect (start -0.8 -0.4) (end 0.8 0.4)
      (stroke (width 0.15) (type solid)) (fill none) (layer "F.Fab"))
    (pad "1" smd roundrect (at -0.7 0 270) (size 0.8 1) (layers "F.Cu" "F.Paste" "F.Mask") (roundrect_rratio 0.2)
      (net 4 "GND") (pintype "passive"))
    (pad "2" smd roundrect (at 0.7 0 270) (size 0.8 1) (layers "F.Cu" "F.Paste" "F.Mask") (roundrect_rratio 0.2)
      (net 1 "VCC3V3") (pintype "passive"))
  )
	(footprint "antmicro-footprints:C_0603_1608Metric" (layer "F.Cu")
    (at 103.047132 99.826324 -90)
    (descr "Capacitor SMD 0603")
    (tags "capacitor 0603")
    (property "Author" "Antmicro")
    (property "Dielectric" "")
    (property "License" "Apache-2.0")
    (property "MPN" "GRM188R60J226MEA0D")
    (property "Manufacturer" "Murata")
    (property "Sheetfile" "daughterboard-supply.kicad_sch")
    (property "Sheetname" "daughterboard-supply")
    (property "Val" "22u")
    (property "Voltage" "")
    (property "ki_description" "SMD Multilayer Ceramic Capacitor, 22 µF, 6.3 V, 0603 [1608 Metric], ± 20%, X5R, GRM Series")
    (property "ki_keywords" "0603, SMT, CAPACITOR, PASSIVE, CERAMIC, MLCC")
    (attr smd)
    (fp_text reference "C36" (at -0.276324 0.747132 90) (layer "F.SilkS")
        (effects (font (size 0.7 0.7) (thickness 0.15)) (justify right bottom))
    )
    (fp_text value "C_22u_0603" (at -1.42757 1.770288 90) (layer "F.Fab")
        (effects (font (size 0.7 0.7) (thickness 0.15)) (justify right bottom))
    )
    (fp_text user "License: Apache-2.0" (at -1.682 5.895 90) (layer "F.Fab") hide
        (effects (font (size 0.7 0.7) (thickness 0.15)) (justify right bottom))
    )
    (fp_text user "Author: Antmicro" (at -1.682 4.894 90) (layer "F.Fab") hide
        (effects (font (size 0.7 0.7) (thickness 0.15)) (justify right bottom))
    )
    (fp_text user "${REFERENCE}" (at -1.682 3.895 90) (layer "F.Fab") hide
        (effects (font (size 0.7 0.7) (thickness 0.15)) (justify right bottom))
    )
    (fp_line (start -0.15 -0.4) (end 0.15 -0.4)
      (stroke (width 0.15) (type solid)) (layer "F.SilkS"))
    (fp_line (start -0.15 0.4) (end 0.15 0.4)
      (stroke (width 0.15) (type solid)) (layer "F.SilkS"))
    (fp_rect (start -1.25 -0.65) (end 1.25 0.65)
      (stroke (width 0.05) (type solid)) (fill none) (layer "F.CrtYd"))
    (fp_rect (start -0.8 -0.4) (end 0.8 0.4)
      (stroke (width 0.15) (type solid)) (fill none) (layer "F.Fab"))
    (pad "1" smd roundrect (at -0.7 0 270) (size 0.8 1) (layers "F.Cu" "F.Paste" "F.Mask") (roundrect_rratio 0.2)
      (net 4 "GND") (pintype "passive"))
    (pad "2" smd roundrect (at 0.7 0 270) (size 0.8 1) (layers "F.Cu" "F.Paste" "F.Mask") (roundrect_rratio 0.2)
      (net 1 "VCC3V3") (pintype "passive"))
  )
	(footprint "antmicro-footprints:L_WE-LHMI-5030" (layer "F.Cu")
    (at 106.047132 104.126324 180)
    (property "Author" "Antmicro")
    (property "IMax" "4.1A")
    (property "ISat" "5.45A")
    (property "License" "Apache-2.0")
    (property "MPN" "74437336033")
    (property "Manufacturer" "Würth Elektronik")
    (property "Sheetfile" "daughterboard-supply.kicad_sch")
    (property "Sheetname" "daughterboard-supply")
    (property "Size" "5.2x5.2")
    (property "Val" "3u3/4.1A")
    (property "ki_description" "Power Inductor (SMT), 3.3 µH, 4.1 A, Shielded, 8.4 A, WE-LHMI")
    (property "ki_keywords" "SMT, INDUCTOR, PASSIVE")
    (attr smd)
    (fp_text reference "L1" (at 3.247132 1.226324 90) (layer "F.SilkS")
        (effects (font (size 0.7 0.7) (thickness 0.15)) (justify left bottom))
    )
    (fp_text value "L_3u3_4.1A_WE-LHMI-5030" (at 0 3.9) (layer "F.Fab")
        (effects (font (size 0.7 0.7) (thickness 0.15)) (justify left bottom))
    )
    (fp_text user "${REFERENCE}" (at -3.5 7.1 180) (layer "F.Fab") hide
        (effects (font (size 0.7 0.7) (thickness 0.15)) (justify left bottom))
    )
    (fp_text user "License: Apache-2.0" (at -3.5 8.3 180) (layer "F.Fab") hide
        (effects (font (size 0.7 0.7) (thickness 0.15)) (justify left bottom))
    )
    (fp_text user "Author: Antmicro" (at -3.5 5.9 180) (layer "F.Fab") hide
        (effects (font (size 0.7 0.7) (thickness 0.15)) (justify left bottom))
    )
    (fp_line (start -2.725 -1.6125) (end -2.725 -1.125)
      (stroke (width 0.15) (type solid)) (layer "F.SilkS"))
    (fp_line (start -2.725 1.6125) (end -2.725 1.125)
      (stroke (width 0.15) (type solid)) (layer "F.SilkS"))
    (fp_line (start -1.6 -2.725) (end 1.6 -2.725)
      (stroke (width 0.15) (type solid)) (layer "F.SilkS"))
    (fp_line (start 1.6 2.725) (end -1.6 2.725)
      (stroke (width 0.15) (type solid)) (layer "F.SilkS"))
    (fp_line (start 2.725 -1.6125) (end 2.725 -1.125)
      (stroke (width 0.15) (type solid)) (layer "F.SilkS"))
    (fp_line (start 2.725 1.6125) (end 2.725 1.125)
      (stroke (width 0.15) (type solid)) (layer "F.SilkS"))
    (fp_arc (start -2.725 -1.6125) (mid -2.392906 -2.401745) (end -1.6 -2.725)
      (stroke (width 0.15) (type solid)) (layer "F.SilkS"))
    (fp_arc (start -1.6 2.725) (mid -2.392906 2.401745) (end -2.725 1.6125)
      (stroke (width 0.15) (type solid)) (layer "F.SilkS"))
    (fp_arc (start 1.6 -2.725) (mid 2.392906 -2.401745) (end 2.725 -1.6125)
      (stroke (width 0.15) (type solid)) (layer "F.SilkS"))
    (fp_arc (start 2.725 1.6125) (mid 2.392906 2.401745) (end 1.6 2.725)
      (stroke (width 0.15) (type solid)) (layer "F.SilkS"))
    (fp_line (start -3.5 1.15) (end -3.5 -1.15)
      (stroke (width 0.05) (type solid)) (layer "F.CrtYd"))
    (fp_line (start -3.1 -2.85) (end 3.1 -2.85)
      (stroke (width 0.05) (type solid)) (layer "F.CrtYd"))
    (fp_line (start -3.1 -1.15) (end -3.5 -1.15)
      (stroke (width 0.05) (type solid)) (layer "F.CrtYd"))
    (fp_line (start -3.1 -1.15) (end -3.1 -2.85)
      (stroke (width 0.05) (type solid)) (layer "F.CrtYd"))
    (fp_line (start -3.1 1.15) (end -3.5 1.15)
      (stroke (width 0.05) (type solid)) (layer "F.CrtYd"))
    (fp_line (start -3.1 2.85) (end -3.1 1.15)
      (stroke (width 0.05) (type solid)) (layer "F.CrtYd"))
    (fp_line (start 3.1 -2.85) (end 3.1 -1.15)
      (stroke (width 0.05) (type solid)) (layer "F.CrtYd"))
    (fp_line (start 3.1 -1.15) (end 3.5 -1.15)
      (stroke (width 0.05) (type solid)) (layer "F.CrtYd"))
    (fp_line (start 3.1 1.15) (end 3.1 2.85)
      (stroke (width 0.05) (type solid)) (layer "F.CrtYd"))
    (fp_line (start 3.1 1.15) (end 3.5 1.15)
      (stroke (width 0.05) (type solid)) (layer "F.CrtYd"))
    (fp_line (start 3.1 2.85) (end -3.1 2.85)
      (stroke (width 0.05) (type solid)) (layer "F.CrtYd"))
    (fp_line (start 3.5 -1.15) (end 3.5 1.15)
      (stroke (width 0.05) (type solid)) (layer "F.CrtYd"))
    (fp_rect (start -2.85 -2.6) (end 2.85 2.6)
      (stroke (width 0.15) (type solid)) (fill none) (layer "F.Fab"))
    (pad "1" smd roundrect (at -2.25 0) (size 2 1.8) (layers "F.Cu" "F.Paste" "F.Mask") (roundrect_rratio 0.1)
      (net 32 "Net-(U4-SW)") (pintype "passive"))
    (pad "2" smd roundrect (at 2.25 0 180) (size 2 1.8) (layers "F.Cu" "F.Paste" "F.Mask") (roundrect_rratio 0.1)
      (net 1 "VCC3V3") (pintype "passive"))
  )
	(footprint "antmicro-footprints:R_0603_1608Metric" (layer "F.Cu")
    (at 173.175 106.25 90)
    (descr "Resistor SMD 0603")
    (tags "resistor SMD 0603")
    (property "Author" "Antmicro")
    (property "Current" "1A")
    (property "DNP" "DNP")
    (property "License" "Apache-2.0")
    (property "MPN" "CR0603-J/-000ELF")
    (property "Manufacturer" "Bourns")
    (property "Sheetfile" "ftdi-module.kicad_sch")
    (property "Sheetname" "FTDI")
    (property "Tolerance" "")
    (property "Val" "0R")
    (property "dnp" "")
    (property "exclude_from_bom" "")
    (property "ki_description" "Zero Ohm Resistor, Jumper, 0603 [1608 Metric], Thick Film, 100 mW, 1 A, Surface Mount Device, CR")
    (property "ki_keywords" "0603, SMT, RESISTOR, PASSIVE")
    (attr smd exclude_from_bom)
    (fp_text reference "R38" (at 0.025 -2.875 90) (layer "F.SilkS")
        (effects (font (size 0.7 0.7) (thickness 0.15)))
    )
    (fp_text value "R_0R_0603" (at 0 1.9 90) (layer "F.Fab") hide
        (effects (font (size 1 1) (thickness 0.15)))
    )
    (fp_text user "Author: Antmicro" (at -1.25 4.9 90) (layer "F.Fab") hide
        (effects (font (size 0.7 0.7) (thickness 0.15)) (justify left bottom))
    )
    (fp_text user "License: Apache-2.0" (at -1.25 5.9 90) (layer "F.Fab") hide
        (effects (font (size 0.7 0.7) (thickness 0.15)) (justify left bottom))
    )
    (fp_text user "${REFERENCE}" (at -1.25 3.898 90) (layer "F.Fab") hide
        (effects (font (size 0.7 0.7) (thickness 0.15)) (justify left bottom))
    )
    (fp_line (start -0.15 -0.4) (end 0.15 -0.4)
      (stroke (width 0.15) (type solid)) (layer "F.SilkS"))
    (fp_line (start -0.15 0.4) (end 0.15 0.4)
      (stroke (width 0.15) (type solid)) (layer "F.SilkS"))
    (fp_rect (start -1.25 -0.65) (end 1.25 0.65)
      (stroke (width 0.05) (type solid)) (fill none) (layer "F.CrtYd"))
    (fp_rect (start -0.8 -0.4) (end 0.8 0.4)
      (stroke (width 0.15) (type solid)) (fill none) (layer "F.Fab"))
    (pad "1" smd roundrect (at -0.7 0 90) (size 0.8 1) (layers "F.Cu" "F.Paste" "F.Mask") (roundrect_rratio 0.2)
      (net 80 "SDA_FTDI") (pintype "passive"))
    (pad "2" smd roundrect (at 0.7 0 90) (size 0.8 1) (layers "F.Cu" "F.Paste" "F.Mask") (roundrect_rratio 0.2)
      (net 18 "SDA") (pintype "passive"))
  )
	(footprint "antmicro-footprints:R_0603_1608Metric" (layer "F.Cu")
    (at 171.675 106.25 90)
    (descr "Resistor SMD 0603")
    (tags "resistor SMD 0603")
    (property "Author" "Antmicro")
    (property "Current" "1A")
    (property "DNP" "DNP")
    (property "License" "Apache-2.0")
    (property "MPN" "CR0603-J/-000ELF")
    (property "Manufacturer" "Bourns")
    (property "Sheetfile" "ftdi-module.kicad_sch")
    (property "Sheetname" "FTDI")
    (property "Tolerance" "")
    (property "Val" "0R")
    (property "dnp" "")
    (property "exclude_from_bom" "")
    (property "ki_description" "Zero Ohm Resistor, Jumper, 0603 [1608 Metric], Thick Film, 100 mW, 1 A, Surface Mount Device, CR")
    (property "ki_keywords" "0603, SMT, RESISTOR, PASSIVE")
    (attr smd exclude_from_bom)
    (fp_text reference "R42" (at 0 -2.675 90) (layer "F.SilkS")
        (effects (font (size 0.7 0.7) (thickness 0.15)))
    )
    (fp_text value "R_0R_0603" (at 0 1.9 90) (layer "F.Fab") hide
        (effects (font (size 1 1) (thickness 0.15)))
    )
    (fp_text user "${REFERENCE}" (at -1.25 3.898 90) (layer "F.Fab") hide
        (effects (font (size 0.7 0.7) (thickness 0.15)) (justify left bottom))
    )
    (fp_text user "Author: Antmicro" (at -1.25 4.9 90) (layer "F.Fab") hide
        (effects (font (size 0.7 0.7) (thickness 0.15)) (justify left bottom))
    )
    (fp_text user "License: Apache-2.0" (at -1.25 5.9 90) (layer "F.Fab") hide
        (effects (font (size 0.7 0.7) (thickness 0.15)) (justify left bottom))
    )
    (fp_line (start -0.15 -0.4) (end 0.15 -0.4)
      (stroke (width 0.15) (type solid)) (layer "F.SilkS"))
    (fp_line (start -0.15 0.4) (end 0.15 0.4)
      (stroke (width 0.15) (type solid)) (layer "F.SilkS"))
    (fp_rect (start -1.25 -0.65) (end 1.25 0.65)
      (stroke (width 0.05) (type solid)) (fill none) (layer "F.CrtYd"))
    (fp_rect (start -0.8 -0.4) (end 0.8 0.4)
      (stroke (width 0.15) (type solid)) (fill none) (layer "F.Fab"))
    (pad "1" smd roundrect (at -0.7 0 90) (size 0.8 1) (layers "F.Cu" "F.Paste" "F.Mask") (roundrect_rratio 0.2)
      (net 77 "GNDD") (pintype "passive"))
    (pad "2" smd roundrect (at 0.7 0 90) (size 0.8 1) (layers "F.Cu" "F.Paste" "F.Mask") (roundrect_rratio 0.2)
      (net 4 "GND") (pintype "passive"))
  )
	(footprint "antmicro-footprints:R_0402_1005Metric" (layer "F.Cu")
    (at 107.147132 96.011324 90)
    (descr "Resistor SMD 0402")
    (tags "resistor SMD 0402")
    (property "Author" "Antmicro")
    (property "License" "Apache-2.0")
    (property "MPN" "CR0402-FX-2151GLF")
    (property "Manufacturer" "Bourns")
    (property "Sheetfile" "daughterboard-supply.kicad_sch")
    (property "Sheetname" "daughterboard-supply")
    (property "Tolerance" "1%")
    (property "Val" "2k15")
    (property "ki_description" "SMD Chip Resistor, 2.15 kohm, ± 1%, 63 mW, 0402 [1005 Metric], Thick Film, General Purpose")
    (property "ki_keywords" "0402, SMT, RESISTOR, PASSIVE")
    (zone_connect 1)
    (attr smd)
    (fp_text reference "R43" (at 0.911324 0.452868 90) (layer "F.SilkS")
        (effects (font (size 0.7 0.7) (thickness 0.15)) (justify left bottom))
    )
    (fp_text value "R_2k15_0402" (at -1.011843 1.772047 90) (layer "F.Fab")
        (effects (font (size 0.7 0.7) (thickness 0.15)) (justify left bottom))
    )
    (fp_text user "${REFERENCE}" (at -0.95 3.168 90) (layer "F.Fab") hide
        (effects (font (size 0.7 0.7) (thickness 0.15)) (justify left bottom))
    )
    (fp_text user "License: Apache-2.0" (at -0.95 5.169 90) (layer "F.Fab") hide
        (effects (font (size 0.7 0.7) (thickness 0.15)) (justify left bottom))
    )
    (fp_text user "Author: Antmicro" (at -0.95 4.169 90) (layer "F.Fab") hide
        (effects (font (size 0.7 0.7) (thickness 0.15)) (justify left bottom))
    )
    (fp_rect (start -0.925 -0.47) (end 0.925 0.47)
      (stroke (width 0.05) (type default)) (fill none) (layer "F.CrtYd"))
    (fp_rect (start -0.5 -0.25) (end 0.5 0.25)
      (stroke (width 0.15) (type solid)) (fill none) (layer "F.Fab"))
    (pad "1" smd roundrect (at -0.48 0 90) (size 0.59 0.64) (layers "F.Cu" "F.Paste" "F.Mask") (roundrect_rratio 0.25)
      (net 112 "Net-(U4-FB)") (pintype "passive"))
    (pad "2" smd roundrect (at 0.48 0 90) (size 0.59 0.64) (layers "F.Cu" "F.Paste" "F.Mask") (roundrect_rratio 0.25)
      (net 1 "VCC3V3") (pintype "passive"))
  )
	(footprint "antmicro-footprints:R_0402_1005Metric" (layer "F.Cu")
    (at 108.147132 96.011324 90)
    (descr "Resistor SMD 0402")
    (tags "resistor SMD 0402")
    (property "Author" "Antmicro")
    (property "License" "Apache-2.0")
    (property "MPN" "CR0402-FX-6800GLF")
    (property "Manufacturer" "Bourns")
    (property "Sheetfile" "daughterboard-supply.kicad_sch")
    (property "Sheetname" "daughterboard-supply")
    (property "Tolerance" "1%")
    (property "Val" "680R")
    (property "ki_description" "SMD Chip Resistor, 680 ohm, ± 1%, 63 mW, 0402 [1005 Metric], Thick Film, General Purpose")
    (property "ki_keywords" "0402, SMT, RESISTOR, PASSIVE")
    (zone_connect 1)
    (attr smd)
    (fp_text reference "R44" (at 0.911324 0.452868 90) (layer "F.SilkS")
        (effects (font (size 0.7 0.7) (thickness 0.15)) (justify left bottom))
    )
    (fp_text value "R_680R_0402" (at -1.011843 1.772047 90) (layer "F.Fab")
        (effects (font (size 0.7 0.7) (thickness 0.15)) (justify left bottom))
    )
    (fp_text user "Author: Antmicro" (at -0.95 4.169 90) (layer "F.Fab") hide
        (effects (font (size 0.7 0.7) (thickness 0.15)) (justify left bottom))
    )
    (fp_text user "${REFERENCE}" (at -0.95 3.168 90) (layer "F.Fab") hide
        (effects (font (size 0.7 0.7) (thickness 0.15)) (justify left bottom))
    )
    (fp_text user "License: Apache-2.0" (at -0.95 5.169 90) (layer "F.Fab") hide
        (effects (font (size 0.7 0.7) (thickness 0.15)) (justify left bottom))
    )
    (fp_rect (start -0.925 -0.47) (end 0.925 0.47)
      (stroke (width 0.05) (type default)) (fill none) (layer "F.CrtYd"))
    (fp_rect (start -0.5 -0.25) (end 0.5 0.25)
      (stroke (width 0.15) (type solid)) (fill none) (layer "F.Fab"))
    (pad "1" smd roundrect (at -0.48 0 90) (size 0.59 0.64) (layers "F.Cu" "F.Paste" "F.Mask") (roundrect_rratio 0.25)
      (net 112 "Net-(U4-FB)") (pintype "passive"))
    (pad "2" smd roundrect (at 0.48 0 90) (size 0.59 0.64) (layers "F.Cu" "F.Paste" "F.Mask") (roundrect_rratio 0.25)
      (net 4 "GND") (pintype "passive"))
  )
)
